# S9S_MB_2U (Grand Teton) — schematic netlist excerpt (pin names and nets, part order shuffled) for the footprints in the layout excerpt that follows; sources: Cadence DE-HDL packaged netlist, KiCad conversion of 03242023_DA0F0TMBIJ0_F0T_Motherboard_J_brd_V01_OCP.brd

J16  SCONN288_ADR50017P087CC  SCONN288_ADR50017-P087CC IO  pkg DDR288S_1-1VXB  page 97
  VIN_BULK0  = P12V_S3_AUX_CPU0_NVDIMM
  RFU0  = TP_CHH_CPU0_DIMM2_FRU_0
  VIN_MGMT  = P3V3_AUX
  HSCL  = I3C_SPD_DDREFGH_CPU0_LVC1_SCL_7
  HSDA  = I3C_SPD_DDREFGH_CPU0_LVC1_SDA
  VSS0  = GND
  DQ0_A  = M_H_CPU0_SA_DQ<0>
  VSS1  = GND
  DQ1_A  = M_H_CPU0_SA_DQ<1>
  VSS2  = GND
  DQS0_A_T  = M_H_CPU0_SA_DQS_DP<0>
  DQS0_A_C  = M_H_CPU0_SA_DQS_DN<0>
  VSS3  = GND
  DQ4_A  = M_H_CPU0_SA_DQ<4>
  VSS4  = GND
  DQ5_A  = M_H_CPU0_SA_DQ<5>
  VSS5  = GND
  DQ8_A  = M_H_CPU0_SA_DQ<8>
  VSS6  = GND
  DQ9_A  = M_H_CPU0_SA_DQ<9>
  VSS7  = GND
  DQS1_A_T  = M_H_CPU0_SA_DQS_DP<1>
  DQS1_A_C  = M_H_CPU0_SA_DQS_DN<1>
  VSS8  = GND
  DQ12_A  = M_H_CPU0_SA_DQ<12>
  VSS9  = GND
  DQ13_A  = M_H_CPU0_SA_DQ<13>
  VSS10  = GND
  DQ16_A  = M_H_CPU0_SA_DQ<16>
  VSS11  = GND
  DQ17_A  = M_H_CPU0_SA_DQ<17>
  VSS12  = GND
  DQS2_A_T  = M_H_CPU0_SA_DQS_DP<2>
  DQS2_A_C  = M_H_CPU0_SA_DQS_DN<2>
  VSS13  = GND
  DQ20_A  = M_H_CPU0_SA_DQ<20>
  VSS14  = GND
  DQ21_A  = M_H_CPU0_SA_DQ<21>
  VSS15  = GND
  DQ24_A  = M_H_CPU0_SA_DQ<24>
  VSS16  = GND
  DQ25_A  = M_H_CPU0_SA_DQ<25>
  VSS17  = GND
  DQS3_A_T  = M_H_CPU0_SA_DQS_DP<3>
  DQS3_A_C  = M_H_CPU0_SA_DQS_DN<3>
  VSS18  = GND
  DQ28_A  = M_H_CPU0_SA_DQ<28>
  VSS19  = GND
  DQ29_A  = M_H_CPU0_SA_DQ<29>
  VSS20  = GND
  CB0_A  = M_H_CPU0_SA_CB<0>
  VSS21  = GND
  CB1_A  = M_H_CPU0_SA_CB<1>
  VSS22  = GND
  DQS4_A_T  = M_H_CPU0_SA_DQS_DP<4>
  DQS4_A_C  = M_H_CPU0_SA_DQS_DN<4>
  VSS23  = GND
  CB4_A  = M_H_CPU0_SA_CB<4>
  VSS24  = GND
  CB5_A  = M_H_CPU0_SA_CB<5>
  VSS25  = GND
  ALERT_N  = M_H_CPU0_ALERT_N
  VSS26  = GND
  CS0_A_N  = M_H_CPU0_SA_CS_N<2>
  VSS27  = GND
  CA0_A  = M_H_CPU0_SA_CA<0>
  VSS28  = GND
  CA2_A  = M_H_CPU0_SA_CA<2>
  VSS29  = GND
  CA4_A  = M_H_CPU0_SA_CA<4>
  VSS30  = GND
  CA6_A  = M_H_CPU0_SA_CA<6>
  VSS31  = GND
  PAR_A  = M_H_CPU0_SA_PAR
  VSS32  = GND
  CA0_B  = M_H_CPU0_SB_CA<0>
  VSS33  = GND
  CA2_B  = M_H_CPU0_SB_CA<2>
  VSS34  = GND
  CA4_B  = M_H_CPU0_SB_CA<4>
  VSS35  = GND
  CA6_B  = M_H_CPU0_SB_CA<6>
  VSS36  = GND
  CS0_B_N  = M_H_CPU0_SB_CS_N<2>
  VSS37  = GND
  \lbd||rsp_a_n\  = M_H_CPU0_SA_RSP<1>
  \lbs||rsp_b_n\  = M_H_CPU0_SB_RSP<1>
  VSS38  = GND
  CB4_B  = M_H_CPU0_SB_CB<4>
  VSS39  = GND
  CB5_B  = M_H_CPU0_SB_CB<5>
  VSS40  = GND
  \dqs9_b_t||tdqs9_b_t||dbi4_b_n\  = M_H_CPU0_SB_DQS_DP<9>
  \dqs9_b_c||tdqs9_b_c\  = M_H_CPU0_SB_DQS_DN<9>
  VSS41  = GND
  CB0_B  = M_H_CPU0_SB_CB<0>
  VSS42  = GND
  CB1_B  = M_H_CPU0_SB_CB<1>
  VSS43  = GND
  DQ0_B  = M_H_CPU0_SB_DQ<0>
  VSS44  = GND
  DQ1_B  = M_H_CPU0_SB_DQ<1>
  VSS45  = GND
  DQS0_B_T  = M_H_CPU0_SB_DQS_DP<0>
  DQS0_B_C  = M_H_CPU0_SB_DQS_DN<0>
  VSS46  = GND
  DQ4_B  = M_H_CPU0_SB_DQ<4>
  VSS47  = GND
  DQ5_B  = M_H_CPU0_SB_DQ<5>
  VSS48  = GND
  DQ8_B  = M_H_CPU0_SB_DQ<8>
  VSS49  = GND
  DQ9_B  = M_H_CPU0_SB_DQ<9>
  VSS50  = GND
  DQS1_B_T  = M_H_CPU0_SB_DQS_DP<1>
  DQS1_B_C  = M_H_CPU0_SB_DQS_DN<1>
  VSS51  = GND
  DQ12_B  = M_H_CPU0_SB_DQ<12>
  VSS52  = GND
  DQ13_B  = M_H_CPU0_SB_DQ<13>
  VSS53  = GND
  DQ16_B  = M_H_CPU0_SB_DQ<16>
  VSS54  = GND
  DQ17_B  = M_H_CPU0_SB_DQ<17>
  VSS55  = GND
  DQS2_B_T  = M_H_CPU0_SB_DQS_DP<2>
  DQS2_B_C  = M_H_CPU0_SB_DQS_DN<2>
  VSS56  = GND
  DQ20_B  = M_H_CPU0_SB_DQ<20>
  VSS57  = GND
  DQ21_B  = M_H_CPU0_SB_DQ<21>
  VSS58  = GND
  DQ24_B  = M_H_CPU0_SB_DQ<24>
  VSS59  = GND
  DQ25_B  = M_H_CPU0_SB_DQ<25>
  VSS60  = GND
  DQS3_B_T  = M_H_CPU0_SB_DQS_DP<3>
  DQS3_B_C  = M_H_CPU0_SB_DQS_DN<3>
  VSS61  = GND
  DQ28_B  = M_H_CPU0_SB_DQ<28>
  VSS62  = GND
  DQ29_B  = M_H_CPU0_SB_DQ<29>
  VSS63  = GND
  RFU1  = TP_CHH_CPU0_DIMM2_FRU_1
  VIN_BULK1  = P12V_S3_AUX_CPU0_NVDIMM
  VIN_BULK2  = P12V_S3_AUX_CPU0_NVDIMM
  \pwr_good||fail_n\  = PWRGD_CHH_CPU0_DIMM2
  HSA  = PD_CHH_CPU0_DIMM2_SAA
  RFU2  = TP_CHH_CPU0_DIMM2_FRU_2
  RFU3  = TP_CHH_CPU0_DIMM2_FRU_3
  VSS64  = GND
  DQ2_A  = M_H_CPU0_SA_DQ<2>
  VSS65  = GND
  DQ3_A  = M_H_CPU0_SA_DQ<3>
  VSS66  = GND
  \dqs5_a_c||tdqs5_a_c||dqs5_a_t||tdqs5_a_t\  = M_H_CPU0_SA_DQS_DN<5>
  \dqs5_a_t||tdqs5_a_t\  = M_H_CPU0_SA_DQS_DP<5>
  VSS67  = GND
  DQ6_A  = M_H_CPU0_SA_DQ<6>
  VSS68  = GND
  DQ7_A  = M_H_CPU0_SA_DQ<7>
  VSS69  = GND
  DQ10_A  = M_H_CPU0_SA_DQ<10>
  VSS70  = GND
  DQ11_A  = M_H_CPU0_SA_DQ<11>
  VSS71  = GND
  \dqs6_a_c||tdqs6_a_c||dqs6_a_t||tdqs6_a_t\  = M_H_CPU0_SA_DQS_DN<6>
  \dqs6_a_t||tdqs6_a_t\  = M_H_CPU0_SA_DQS_DP<6>
  VSS72  = GND
  DQ14_A  = M_H_CPU0_SA_DQ<14>
  VSS73  = GND
  DQ15_A  = M_H_CPU0_SA_DQ<15>
  VSS74  = GND
  DQ18_A  = M_H_CPU0_SA_DQ<18>
  VSS75  = GND
  DQ19_A  = M_H_CPU0_SA_DQ<19>
  VSS76  = GND
  \dqs7_a_c||tdqs7_a_c\  = M_H_CPU0_SA_DQS_DN<7>
  \dqs7_a_t||tdqs7_a_t\  = M_H_CPU0_SA_DQS_DP<7>
  VSS77  = GND
  DQ22_A  = M_H_CPU0_SA_DQ<22>
  VSS78  = GND
  DQ23_A  = M_H_CPU0_SA_DQ<23>
  VSS79  = GND
  DQ26_A  = M_H_CPU0_SA_DQ<26>
  VSS80  = GND
  DQ27_A  = M_H_CPU0_SA_DQ<27>
  VSS81  = GND
  \dqs8_a_c||tdqs8_a_c\  = M_H_CPU0_SA_DQS_DN<8>
  \dqs8_a_t||tdqs8_a_t\  = M_H_CPU0_SA_DQS_DP<8>
  VSS82  = GND
  DQ30_A  = M_H_CPU0_SA_DQ<30>
  VSS83  = GND
  DQ31_A  = M_H_CPU0_SA_DQ<31>
  VSS84  = GND
  CB2_A  = M_H_CPU0_SA_CB<2>
  VSS85  = GND
  CB3_A  = M_H_CPU0_SA_CB<3>
  VSS86  = GND
  \dqs9_a_c||tdqs9_a_c\  = M_H_CPU0_SA_DQS_DN<9>
  \dqs9_a_t||tdqs9_a_t\  = M_H_CPU0_SA_DQS_DP<9>
  VSS87  = GND
  CB6_A  = M_H_CPU0_SA_CB<6>
  VSS88  = GND
  CB7_A  = M_H_CPU0_SA_CB<7>
  VSS89  = GND
  RESET_N  = RST_M_GH_CPU0_FPGA_N
  VSS90  = GND
  CS1_A_N  = M_H_CPU0_SA_CS_N<3>
  VSS91  = GND
  CA1_A  = M_H_CPU0_SA_CA<1>
  VSS92  = GND
  CA3_A  = M_H_CPU0_SA_CA<3>
  VSS93  = GND
  CA5_A  = M_H_CPU0_SA_CA<5>
  VSS94  = GND
  CK_T  = M_H_CPU0_CLK_DP<1>
  CK_C  = M_H_CPU0_CLK_DN<1>
  VSS95  = GND
  RFU4  = TP_CHH_CPU0_DIMM2_FRU_4
  CA1_B  = M_H_CPU0_SB_CA<1>
  VSS96  = GND
  CA3_B  = M_H_CPU0_SB_CA<3>
  VSS97  = GND
  CA5_B  = M_H_CPU0_SB_CA<5>
  VSS98  = GND
  PAR_B  = M_H_CPU0_SB_PAR
  VSS99  = GND
  CS1_B_N  = M_H_CPU0_SB_CS_N<3>
  VSS100  = GND
  RFU5  = TP_CHH_CPU0_DIMM2_FRU_5
  RFU6  = TP_CHH_CPU0_DIMM2_FRU_6
  VSS101  = GND
  CB6_B  = M_H_CPU0_SB_CB<6>
  VSS102  = GND
  CB7_B  = M_H_CPU0_SB_CB<7>
  VSS103  = GND
  DQS4_B_C  = M_H_CPU0_SB_DQS_DN<4>
  DQS4_B_T  = M_H_CPU0_SB_DQS_DP<4>
  VSS104  = GND
  CB2_B  = M_H_CPU0_SB_CB<2>
  VSS105  = GND
  CB3_B  = M_H_CPU0_SB_CB<3>
  VSS106  = GND
  DQ2_B  = M_H_CPU0_SB_DQ<2>
  VSS107  = GND
  DQ3_B  = M_H_CPU0_SB_DQ<3>
  VSS108  = GND
  \dqs5_b_c||tdqs5_b_c\  = M_H_CPU0_SB_DQS_DN<5>
  \dqs5_b_t||tdqs5_b_t\  = M_H_CPU0_SB_DQS_DP<5>
  VSS109  = GND
  DQ6_B  = M_H_CPU0_SB_DQ<6>
  VSS110  = GND
  DQ7_B  = M_H_CPU0_SB_DQ<7>
  VSS111  = GND
  DQ10_B  = M_H_CPU0_SB_DQ<10>
  VSS112  = GND
  DQ11_B  = M_H_CPU0_SB_DQ<11>
  VSS113  = GND
  \dqs6_b_c||tdqs6_b_c\  = M_H_CPU0_SB_DQS_DN<6>
  \dqs6_b_t||tdqs6_b_t\  = M_H_CPU0_SB_DQS_DP<6>
  VSS114  = GND
  DQ14_B  = M_H_CPU0_SB_DQ<14>
  VSS115  = GND
  DQ15_B  = M_H_CPU0_SB_DQ<15>
  VSS116  = GND
  DQ18_B  = M_H_CPU0_SB_DQ<18>
  VSS117  = GND
  DQ19_B  = M_H_CPU0_SB_DQ<19>
  VSS118  = GND
  \dqs7_b_c||tdqs7_b_c\  = M_H_CPU0_SB_DQS_DN<7>
  \dqs7_b_t||tdqs7_b_t\  = M_H_CPU0_SB_DQS_DP<7>
  VSS119  = GND
  DQ22_B  = M_H_CPU0_SB_DQ<22>
  VSS120  = GND
  DQ23_B  = M_H_CPU0_SB_DQ<23>
  VSS121  = GND
  DQ26_B  = M_H_CPU0_SB_DQ<26>
  VSS122  = GND
  DQ27_B  = M_H_CPU0_SB_DQ<27>
  VSS123  = GND
  \dqs8_b_c||tdqs8_b_c\  = M_H_CPU0_SB_DQS_DN<8>
  \dqs8_b_t||tdqs8_b_t\  = M_H_CPU0_SB_DQS_DP<8>
  VSS124  = GND
  DQ30_B  = M_H_CPU0_SB_DQ<30>
  VSS125  = GND
  DQ31_B  = M_H_CPU0_SB_DQ<31>
  VSS126  = GND
  G1  = GND
  G2  = GND
  G3  = GND

(kicad_pcb
	(version 20260206)
	(generator "pcbnew")
	(generator_version "10.0")
	(general
		(thickness 1.6)
		(legacy_teardrops no)
	)
	(paper "A4")
	(title_block
		(title "03242023_DA0F0TMBIJ0_F0T_Motherboard_J_brd_V01_OCP.brd")
		(comment 1 "Grand Teton / footprint 1690 of 6105 (J16), pads 183-228 of 291")
	)
	(layers
		(0 "F.Cu" signal "TOP")
		(4 "In1.Cu" signal "GND")
		(6 "In2.Cu" signal "IN1")
		(8 "In3.Cu" signal "GND1")
		(10 "In4.Cu" signal "IN2")
		(12 "In5.Cu" signal "GND2")
		(14 "In6.Cu" signal "IN3")
		(16 "In7.Cu" signal "GND3")
		(18 "In8.Cu" signal "VCC")
		(20 "In9.Cu" signal "VCC1")
		(22 "In10.Cu" signal "GND4")
		(24 "In11.Cu" signal "IN4")
		(26 "In12.Cu" signal "GND5")
		(28 "In13.Cu" signal "IN5")
		(30 "In14.Cu" signal "GND6")
		(32 "In15.Cu" signal "IN6")
		(34 "In16.Cu" signal "GND7")
		(2 "B.Cu" signal "BOTTOM")
		(9 "F.Adhes" user "F.Adhesive")
		(11 "B.Adhes" user "B.Adhesive")
		(13 "F.Paste" user "Package Geometry/Pastemask Top")
		(15 "B.Paste" user "Package Geometry/Pastemask Bottom")
		(5 "F.SilkS" user "Ref Des/Silkscreen Top")
		(7 "B.SilkS" user "Ref Des/Silkscreen Bottom")
		(1 "F.Mask" user "Board Geometry/Soldermask Top")
		(3 "B.Mask" user "Board Geometry/Soldermask Bottom")
		(17 "Dwgs.User" user "User.Drawings")
		(19 "Cmts.User" user "User.Comments")
		(21 "Eco1.User" user "User.Eco1")
		(23 "Eco2.User" user "User.Eco2")
		(25 "Edge.Cuts" user "Board Geometry/Outline")
		(27 "Margin" user)
		(31 "F.CrtYd" user "Package Geometry/Place Bound Top")
		(29 "B.CrtYd" user "Package Geometry/Place Bound Bottom")
		(35 "F.Fab" user "Ref Des/Assembly Top")
		(33 "B.Fab" user "Ref Des/Assembly Bottom")
	)
	(footprint ""
		(layer "F.Cu")
		(at 454.066148 -258.091686)
		(property "Reference" "J16"
			(at -0.279908 -81.779872 0)
			(unlocked yes)
			(layer "F.SilkS")
			(effects
				(font
					(size 0.7874 0.5842)
					(thickness 0.1524)
				)
				(justify left)
			)
		)
		(property "Value" ""
			(at 0 0 0)
			(layer "F.Fab")
			(effects
				(font
					(size 1.27 1.27)
				)
			)
		)
		(duplicate_pad_numbers_are_jumpers no)
		(pad "183" smd rect
			(at 2.050034 -31.025084 270)
			(size 0.519938 1.4986)
			(layers "F.Cu" "F.Mask" "F.Paste")
			(net "M_H_CPU0_SA_DQ<23>")
		)
		(pad "184" smd rect
			(at 2.050034 -30.174946 270)
			(size 0.519938 1.4986)
			(layers "F.Cu" "F.Mask" "F.Paste")
			(net "GND")
		)
		(pad "185" smd rect
			(at 2.050034 -29.325062 270)
			(size 0.519938 1.4986)
			(layers "F.Cu" "F.Mask" "F.Paste")
			(net "M_H_CPU0_SA_DQ<26>")
		)
		(pad "186" smd rect
			(at 2.050034 -28.474924 270)
			(size 0.519938 1.4986)
			(layers "F.Cu" "F.Mask" "F.Paste")
			(net "GND")
		)
		(pad "187" smd rect
			(at 2.050034 -27.62504 270)
			(size 0.519938 1.4986)
			(layers "F.Cu" "F.Mask" "F.Paste")
			(net "M_H_CPU0_SA_DQ<27>")
		)
		(pad "188" smd rect
			(at 2.050034 -26.774902 270)
			(size 0.519938 1.4986)
			(layers "F.Cu" "F.Mask" "F.Paste")
			(net "GND")
		)
		(pad "189" smd rect
			(at 2.050034 -25.925018 270)
			(size 0.519938 1.4986)
			(layers "F.Cu" "F.Mask" "F.Paste")
			(net "M_H_CPU0_SA_DQS_DN<8>")
		)
		(pad "190" smd rect
			(at 2.050034 -25.07488 270)
			(size 0.519938 1.4986)
			(layers "F.Cu" "F.Mask" "F.Paste")
			(net "M_H_CPU0_SA_DQS_DP<8>")
		)
		(pad "191" smd rect
			(at 2.050034 -24.224996 270)
			(size 0.519938 1.4986)
			(layers "F.Cu" "F.Mask" "F.Paste")
			(net "GND")
		)
		(pad "192" smd rect
			(at 2.050034 -23.375112 270)
			(size 0.519938 1.4986)
			(layers "F.Cu" "F.Mask" "F.Paste")
			(net "M_H_CPU0_SA_DQ<30>")
		)
		(pad "193" smd rect
			(at 2.050034 -22.524974 270)
			(size 0.519938 1.4986)
			(layers "F.Cu" "F.Mask" "F.Paste")
			(net "GND")
		)
		(pad "194" smd rect
			(at 2.050034 -21.67509 270)
			(size 0.519938 1.4986)
			(layers "F.Cu" "F.Mask" "F.Paste")
			(net "M_H_CPU0_SA_DQ<31>")
		)
		(pad "195" smd rect
			(at 2.050034 -20.824952 270)
			(size 0.519938 1.4986)
			(layers "F.Cu" "F.Mask" "F.Paste")
			(net "GND")
		)
		(pad "196" smd rect
			(at 2.050034 -19.975068 270)
			(size 0.519938 1.4986)
			(layers "F.Cu" "F.Mask" "F.Paste")
			(net "M_H_CPU0_SA_CB<2>")
		)
		(pad "197" smd rect
			(at 2.050034 -19.12493 270)
			(size 0.519938 1.4986)
			(layers "F.Cu" "F.Mask" "F.Paste")
			(net "GND")
		)
		(pad "198" smd rect
			(at 2.050034 -18.275046 270)
			(size 0.519938 1.4986)
			(layers "F.Cu" "F.Mask" "F.Paste")
			(net "M_H_CPU0_SA_CB<3>")
		)
		(pad "199" smd rect
			(at 2.050034 -17.424908 270)
			(size 0.519938 1.4986)
			(layers "F.Cu" "F.Mask" "F.Paste")
			(net "GND")
		)
		(pad "200" smd rect
			(at 2.050034 -16.575024 270)
			(size 0.519938 1.4986)
			(layers "F.Cu" "F.Mask" "F.Paste")
			(net "M_H_CPU0_SA_DQS_DN<9>")
		)
		(pad "201" smd rect
			(at 2.050034 -15.724886 270)
			(size 0.519938 1.4986)
			(layers "F.Cu" "F.Mask" "F.Paste")
			(net "M_H_CPU0_SA_DQS_DP<9>")
		)
		(pad "202" smd rect
			(at 2.050034 -14.875002 270)
			(size 0.519938 1.4986)
			(layers "F.Cu" "F.Mask" "F.Paste")
			(net "GND")
		)
		(pad "203" smd rect
			(at 2.050034 -14.025118 270)
			(size 0.519938 1.4986)
			(layers "F.Cu" "F.Mask" "F.Paste")
			(net "M_H_CPU0_SA_CB<6>")
		)
		(pad "204" smd rect
			(at 2.050034 -13.17498 270)
			(size 0.519938 1.4986)
			(layers "F.Cu" "F.Mask" "F.Paste")
			(net "GND")
		)
		(pad "205" smd rect
			(at 2.050034 -12.325096 270)
			(size 0.519938 1.4986)
			(layers "F.Cu" "F.Mask" "F.Paste")
			(net "M_H_CPU0_SA_CB<7>")
		)
		(pad "206" smd rect
			(at 2.050034 -11.474958 270)
			(size 0.519938 1.4986)
			(layers "F.Cu" "F.Mask" "F.Paste")
			(net "GND")
		)
		(pad "207" smd rect
			(at 2.050034 -10.625074 270)
			(size 0.519938 1.4986)
			(layers "F.Cu" "F.Mask" "F.Paste")
			(net "RST_M_GH_CPU0_FPGA_N")
		)
		(pad "208" smd rect
			(at 2.050034 -9.774936 270)
			(size 0.519938 1.4986)
			(layers "F.Cu" "F.Mask" "F.Paste")
			(net "GND")
		)
		(pad "209" smd rect
			(at 2.050034 -8.925052 270)
			(size 0.519938 1.4986)
			(layers "F.Cu" "F.Mask" "F.Paste")
			(net "M_H_CPU0_SA_CS_N<3>")
		)
		(pad "210" smd rect
			(at 2.050034 -8.074914 270)
			(size 0.519938 1.4986)
			(layers "F.Cu" "F.Mask" "F.Paste")
			(net "GND")
		)
		(pad "211" smd rect
			(at 2.050034 -7.22503 270)
			(size 0.519938 1.4986)
			(layers "F.Cu" "F.Mask" "F.Paste")
			(net "M_H_CPU0_SA_CA<1>")
		)
		(pad "212" smd rect
			(at 2.050034 -6.374892 270)
			(size 0.519938 1.4986)
			(layers "F.Cu" "F.Mask" "F.Paste")
			(net "GND")
		)
		(pad "213" smd rect
			(at 2.050034 -5.525008 270)
			(size 0.519938 1.4986)
			(layers "F.Cu" "F.Mask" "F.Paste")
			(net "M_H_CPU0_SA_CA<3>")
		)
		(pad "214" smd rect
			(at 2.050034 -4.675124 270)
			(size 0.519938 1.4986)
			(layers "F.Cu" "F.Mask" "F.Paste")
			(net "GND")
		)
		(pad "215" smd rect
			(at 2.050034 -3.824986 270)
			(size 0.519938 1.4986)
			(layers "F.Cu" "F.Mask" "F.Paste")
			(net "M_H_CPU0_SA_CA<5>")
		)
		(pad "216" smd rect
			(at 2.050034 -2.975102 270)
			(size 0.519938 1.4986)
			(layers "F.Cu" "F.Mask" "F.Paste")
			(net "GND")
		)
		(pad "217" smd rect
			(at 2.050034 -2.124964 270)
			(size 0.519938 1.4986)
			(layers "F.Cu" "F.Mask" "F.Paste")
			(net "M_H_CPU0_CLK_DP<1>")
		)
		(pad "218" smd rect
			(at 2.050034 -1.27508 270)
			(size 0.519938 1.4986)
			(layers "F.Cu" "F.Mask" "F.Paste")
			(net "M_H_CPU0_CLK_DN<1>")
		)
		(pad "219" smd rect
			(at 2.050034 -0.424942 270)
			(size 0.519938 1.4986)
			(layers "F.Cu" "F.Mask" "F.Paste")
			(net "GND")
		)
		(pad "220" smd rect
			(at 2.050034 5.525008 270)
			(size 0.519938 1.4986)
			(layers "F.Cu" "F.Mask" "F.Paste")
			(net "TP_CHH_CPU0_DIMM2_FRU_4")
		)
		(pad "221" smd rect
			(at 2.050034 6.374892 270)
			(size 0.519938 1.4986)
			(layers "F.Cu" "F.Mask" "F.Paste")
			(net "M_H_CPU0_SB_CA<1>")
		)
		(pad "222" smd rect
			(at 2.050034 7.22503 270)
			(size 0.519938 1.4986)
			(layers "F.Cu" "F.Mask" "F.Paste")
			(net "GND")
		)
		(pad "223" smd rect
			(at 2.050034 8.074914 270)
			(size 0.519938 1.4986)
			(layers "F.Cu" "F.Mask" "F.Paste")
			(net "M_H_CPU0_SB_CA<3>")
		)
		(pad "224" smd rect
			(at 2.050034 8.925052 270)
			(size 0.519938 1.4986)
			(layers "F.Cu" "F.Mask" "F.Paste")
			(net "GND")
		)
		(pad "225" smd rect
			(at 2.050034 9.774936 270)
			(size 0.519938 1.4986)
			(layers "F.Cu" "F.Mask" "F.Paste")
			(net "M_H_CPU0_SB_CA<5>")
		)
		(pad "226" smd rect
			(at 2.050034 10.625074 270)
			(size 0.519938 1.4986)
			(layers "F.Cu" "F.Mask" "F.Paste")
			(net "GND")
		)
		(pad "227" smd rect
			(at 2.050034 11.474958 270)
			(size 0.519938 1.4986)
			(layers "F.Cu" "F.Mask" "F.Paste")
			(net "M_H_CPU0_SB_PAR")
		)
		(pad "228" smd rect
			(at 2.050034 12.325096 270)
			(size 0.519938 1.4986)
			(layers "F.Cu" "F.Mask" "F.Paste")
			(net "GND")
		)
	)
)
